# T6G (Grand Teton) — schematic netlist excerpt (pin names and nets, part order shuffled) for the footprints in the layout excerpt that follows; sources: Cadence DE-HDL packaged netlist, KiCad conversion of 04192023_DAF0TMB3IC0_F0TG_MB_C_brd_V02_OCP.brd

C295  Q_CAP  10PF 50V 5% EMPTY  pkg 0402  page 210 : A = SVID_PVDDCR_CPU0_P1_SVTO ; B = GND
R3436  Q_RES  100K 1% CHIP  pkg 0402LF  page 126 : A = P3V3_AUX ; B = GPU_HMC_PRSNT_ISO_N

(kicad_pcb
	(version 20260206)
	(generator "pcbnew")
	(generator_version "10.0")
	(general
		(thickness 1.6)
		(legacy_teardrops no)
	)
	(paper "A4")
	(title_block
		(title "04192023_DAF0TMB3IC0_F0TG_MB_C_brd_V02_OCP.brd")
		(comment 1 "Grand Teton / footprints 45-46 of 8354")
	)
	(layers
		(0 "F.Cu" signal "TOP")
		(4 "In1.Cu" signal "GND")
		(6 "In2.Cu" signal "IN1")
		(8 "In3.Cu" signal "GND1")
		(10 "In4.Cu" signal "IN2")
		(12 "In5.Cu" signal "GND2")
		(14 "In6.Cu" signal "IN3")
		(16 "In7.Cu" signal "GND3")
		(18 "In8.Cu" signal "VCC")
		(20 "In9.Cu" signal "VCC1")
		(22 "In10.Cu" signal "GND4")
		(24 "In11.Cu" signal "IN4")
		(26 "In12.Cu" signal "GND5")
		(28 "In13.Cu" signal "IN5")
		(30 "In14.Cu" signal "GND6")
		(32 "In15.Cu" signal "IN6")
		(34 "In16.Cu" signal "GND7")
		(2 "B.Cu" signal "BOTTOM")
		(9 "F.Adhes" user "F.Adhesive")
		(11 "B.Adhes" user "B.Adhesive")
		(13 "F.Paste" user "Package Geometry/Pastemask Top")
		(15 "B.Paste" user "Package Geometry/Pastemask Bottom")
		(5 "F.SilkS" user "Ref Des/Silkscreen Top")
		(7 "B.SilkS" user "Ref Des/Silkscreen Bottom")
		(1 "F.Mask" user "Board Geometry/Soldermask Top")
		(3 "B.Mask" user "Board Geometry/Soldermask Bottom")
		(17 "Dwgs.User" user "User.Drawings")
		(19 "Cmts.User" user "User.Comments")
		(21 "Eco1.User" user "User.Eco1")
		(23 "Eco2.User" user "User.Eco2")
		(25 "Edge.Cuts" user "Board Geometry/Outline")
		(27 "Margin" user)
		(31 "F.CrtYd" user "Package Geometry/Place Bound Top")
		(29 "B.CrtYd" user "Package Geometry/Place Bound Bottom")
		(35 "F.Fab" user "Ref Des/Assembly Top")
		(33 "B.Fab" user "Ref Des/Assembly Bottom")
	)
	(footprint ""
		(layer "F.Cu")
		(at 118.491 -421.513)
		(property "Reference" "R3436"
			(at 0 0 0)
			(layer "F.SilkS")
			(hide yes)
			(effects
				(font
					(size 1.27 1.27)
				)
			)
		)
		(property "Value" ""
			(at 0 0 0)
			(layer "F.Fab")
			(effects
				(font
					(size 1.27 1.27)
				)
			)
		)
		(duplicate_pad_numbers_are_jumpers no)
		(fp_line
			(start -0.7874 -0.4064)
			(end 0.7874 -0.4064)
			(stroke
				(width 0.1524)
				(type default)
			)
			(layer "F.SilkS")
		)
		(fp_line
			(start -0.7874 0.4064)
			(end -0.7874 -0.4064)
			(stroke
				(width 0.1524)
				(type default)
			)
			(layer "F.SilkS")
		)
		(fp_line
			(start 0.7874 -0.4064)
			(end 0.7874 0.4064)
			(stroke
				(width 0.1524)
				(type default)
			)
			(layer "F.SilkS")
		)
		(fp_line
			(start 0.7874 0.4064)
			(end -0.7874 0.4064)
			(stroke
				(width 0.1524)
				(type default)
			)
			(layer "F.SilkS")
		)
		(fp_line
			(start -0.67945 -0.305054)
			(end -0.12065 -0.305054)
			(stroke
				(width 0.1)
				(type default)
			)
			(layer "F.Fab")
		)
		(fp_line
			(start -0.67945 0.3048)
			(end -0.67945 -0.305054)
			(stroke
				(width 0.1)
				(type default)
			)
			(layer "F.Fab")
		)
		(fp_line
			(start -0.12065 -0.305054)
			(end -0.12065 -0.2794)
			(stroke
				(width 0.1)
				(type default)
			)
			(layer "F.Fab")
		)
		(fp_line
			(start -0.12065 -0.2794)
			(end 0.12065 -0.2794)
			(stroke
				(width 0.1)
				(type default)
			)
			(layer "F.Fab")
		)
		(fp_line
			(start -0.12065 0.2794)
			(end -0.12065 0.3048)
			(stroke
				(width 0.1)
				(type default)
			)
			(layer "F.Fab")
		)
		(fp_line
			(start -0.12065 0.3048)
			(end -0.67945 0.3048)
			(stroke
				(width 0.1)
				(type default)
			)
			(layer "F.Fab")
		)
		(fp_line
			(start 0.120396 0.2794)
			(end -0.12065 0.2794)
			(stroke
				(width 0.1)
				(type default)
			)
			(layer "F.Fab")
		)
		(fp_line
			(start 0.120396 0.3048)
			(end 0.120396 0.2794)
			(stroke
				(width 0.1)
				(type default)
			)
			(layer "F.Fab")
		)
		(fp_line
			(start 0.12065 -0.3048)
			(end 0.67945 -0.3048)
			(stroke
				(width 0.1)
				(type default)
			)
			(layer "F.Fab")
		)
		(fp_line
			(start 0.12065 -0.2794)
			(end 0.12065 -0.3048)
			(stroke
				(width 0.1)
				(type default)
			)
			(layer "F.Fab")
		)
		(fp_line
			(start 0.67945 -0.3048)
			(end 0.67945 0.3048)
			(stroke
				(width 0.1)
				(type default)
			)
			(layer "F.Fab")
		)
		(fp_line
			(start 0.67945 0.3048)
			(end 0.120396 0.3048)
			(stroke
				(width 0.1)
				(type default)
			)
			(layer "F.Fab")
		)
		(pad "1" smd circle
			(at -0.40005 0)
			(size 0 0)
			(layers "F.Cu" "F.Mask" "F.Paste")
			(net "P3V3_AUX")
		)
		(pad "2" smd circle
			(at 0.40005 0)
			(size 0 0)
			(layers "F.Cu" "F.Mask" "F.Paste")
			(net "GPU_HMC_PRSNT_ISO_N")
		)
	)
	(footprint ""
		(layer "F.Cu")
		(at 88.177878 -148.94941 180)
		(property "Reference" "C295"
			(at 0 0 180)
			(layer "F.SilkS")
			(hide yes)
			(effects
				(font
					(size 1.27 1.27)
				)
			)
		)
		(property "Value" ""
			(at 0 0 180)
			(layer "F.Fab")
			(effects
				(font
					(size 1.27 1.27)
				)
			)
		)
		(duplicate_pad_numbers_are_jumpers no)
		(fp_line
			(start 0.7874 0.4064)
			(end -0.7874 0.4064)
			(stroke
				(width 0.1524)
				(type default)
			)
			(layer "F.SilkS")
		)
		(fp_line
			(start 0.7874 -0.4064)
			(end 0.7874 0.4064)
			(stroke
				(width 0.1524)
				(type default)
			)
			(layer "F.SilkS")
		)
		(fp_line
			(start -0.7874 0.4064)
			(end -0.7874 -0.4064)
			(stroke
				(width 0.1524)
				(type default)
			)
			(layer "F.SilkS")
		)
		(fp_line
			(start -0.7874 -0.4064)
			(end 0.7874 -0.4064)
			(stroke
				(width 0.1524)
				(type default)
			)
			(layer "F.SilkS")
		)
		(fp_line
			(start 0.67945 0.3048)
			(end 0.120396 0.3048)
			(stroke
				(width 0.1)
				(type default)
			)
			(layer "F.Fab")
		)
		(fp_line
			(start 0.67945 -0.3048)
			(end 0.67945 0.3048)
			(stroke
				(width 0.1)
				(type default)
			)
			(layer "F.Fab")
		)
		(fp_line
			(start 0.12065 -0.2794)
			(end 0.12065 -0.3048)
			(stroke
				(width 0.1)
				(type default)
			)
			(layer "F.Fab")
		)
		(fp_line
			(start 0.12065 -0.3048)
			(end 0.67945 -0.3048)
			(stroke
				(width 0.1)
				(type default)
			)
			(layer "F.Fab")
		)
		(fp_line
			(start 0.120396 0.3048)
			(end 0.120396 0.2794)
			(stroke
				(width 0.1)
				(type default)
			)
			(layer "F.Fab")
		)
		(fp_line
			(start 0.120396 0.2794)
			(end -0.12065 0.2794)
			(stroke
				(width 0.1)
				(type default)
			)
			(layer "F.Fab")
		)
		(fp_line
			(start -0.12065 0.3048)
			(end -0.67945 0.3048)
			(stroke
				(width 0.1)
				(type default)
			)
			(layer "F.Fab")
		)
		(fp_line
			(start -0.12065 0.2794)
			(end -0.12065 0.3048)
			(stroke
				(width 0.1)
				(type default)
			)
			(layer "F.Fab")
		)
		(fp_line
			(start -0.12065 -0.2794)
			(end 0.12065 -0.2794)
			(stroke
				(width 0.1)
				(type default)
			)
			(layer "F.Fab")
		)
		(fp_line
			(start -0.12065 -0.305054)
			(end -0.12065 -0.2794)
			(stroke
				(width 0.1)
				(type default)
			)
			(layer "F.Fab")
		)
		(fp_line
			(start -0.67945 0.3048)
			(end -0.67945 -0.305054)
			(stroke
				(width 0.1)
				(type default)
			)
			(layer "F.Fab")
		)
		(fp_line
			(start -0.67945 -0.305054)
			(end -0.12065 -0.305054)
			(stroke
				(width 0.1)
				(type default)
			)
			(layer "F.Fab")
		)
		(pad "1" smd circle
			(at -0.40005 0 180)
			(size 0 0)
			(layers "F.Cu" "F.Mask" "F.Paste")
			(net "SVID_PVDDCR_CPU0_P1_SVTO")
		)
		(pad "2" smd circle
			(at 0.40005 0 180)
			(size 0 0)
			(layers "F.Cu" "F.Mask" "F.Paste")
			(net "GND")
		)
	)
)
